# T6G (Grand Teton) — schematic netlist excerpt (pin names and nets, part order shuffled) for the footprints in the layout excerpt that follows; sources: Cadence DE-HDL packaged netlist, KiCad conversion of 04192023_DAF0TMB3IC0_F0TG_MB_C_brd_V02_OCP.brd

R6023  Q_RES  2K 5% EMPTY  pkg 0402LF  page 151 : A = P3V3_AUX ; B = SGPIO_SCM_LD_<1>
C2300  Q_CAP  22UF 4V 20% X6S  pkg C0402  page 73 : A = PVDDCR_CPU0_P1 ; B = GND

(kicad_pcb
	(version 20260206)
	(generator "pcbnew")
	(generator_version "10.0")
	(general
		(thickness 1.6)
		(legacy_teardrops no)
	)
	(paper "A4")
	(title_block
		(title "04192023_DAF0TMB3IC0_F0TG_MB_C_brd_V02_OCP.brd")
		(comment 1 "Grand Teton / footprints 5573-5574 of 8354")
	)
	(layers
		(0 "F.Cu" signal "TOP")
		(4 "In1.Cu" signal "GND")
		(6 "In2.Cu" signal "IN1")
		(8 "In3.Cu" signal "GND1")
		(10 "In4.Cu" signal "IN2")
		(12 "In5.Cu" signal "GND2")
		(14 "In6.Cu" signal "IN3")
		(16 "In7.Cu" signal "GND3")
		(18 "In8.Cu" signal "VCC")
		(20 "In9.Cu" signal "VCC1")
		(22 "In10.Cu" signal "GND4")
		(24 "In11.Cu" signal "IN4")
		(26 "In12.Cu" signal "GND5")
		(28 "In13.Cu" signal "IN5")
		(30 "In14.Cu" signal "GND6")
		(32 "In15.Cu" signal "IN6")
		(34 "In16.Cu" signal "GND7")
		(2 "B.Cu" signal "BOTTOM")
		(9 "F.Adhes" user "F.Adhesive")
		(11 "B.Adhes" user "B.Adhesive")
		(13 "F.Paste" user "Package Geometry/Pastemask Top")
		(15 "B.Paste" user "Package Geometry/Pastemask Bottom")
		(5 "F.SilkS" user "Ref Des/Silkscreen Top")
		(7 "B.SilkS" user "Ref Des/Silkscreen Bottom")
		(1 "F.Mask" user "Board Geometry/Soldermask Top")
		(3 "B.Mask" user "Board Geometry/Soldermask Bottom")
		(17 "Dwgs.User" user "User.Drawings")
		(19 "Cmts.User" user "User.Comments")
		(21 "Eco1.User" user "User.Eco1")
		(23 "Eco2.User" user "User.Eco2")
		(25 "Edge.Cuts" user "Board Geometry/Outline")
		(27 "Margin" user)
		(31 "F.CrtYd" user "Package Geometry/Place Bound Top")
		(29 "B.CrtYd" user "Package Geometry/Place Bound Bottom")
		(35 "F.Fab" user "Ref Des/Assembly Top")
		(33 "B.Fab" user "Ref Des/Assembly Bottom")
	)
	(footprint ""
		(layer "B.Cu")
		(at 104.716834 -249.368564 180)
		(property "Reference" "C2300"
			(at 0 0 0)
			(layer "B.SilkS")
			(hide yes)
			(effects
				(font
					(size 1.27 1.27)
				)
				(justify mirror)
			)
		)
		(property "Value" ""
			(at 0 0 0)
			(layer "B.Fab")
			(effects
				(font
					(size 1.27 1.27)
				)
				(justify mirror)
			)
		)
		(duplicate_pad_numbers_are_jumpers no)
		(fp_line
			(start 0.7874 0.4064)
			(end 0.7874 -0.4064)
			(stroke
				(width 0.1524)
				(type default)
			)
			(layer "B.SilkS")
		)
		(fp_line
			(start 0.7874 -0.4064)
			(end -0.7874 -0.4064)
			(stroke
				(width 0.1524)
				(type default)
			)
			(layer "B.SilkS")
		)
		(fp_line
			(start -0.7874 0.4064)
			(end 0.7874 0.4064)
			(stroke
				(width 0.1524)
				(type default)
			)
			(layer "B.SilkS")
		)
		(fp_line
			(start -0.7874 -0.4064)
			(end -0.7874 0.4064)
			(stroke
				(width 0.1524)
				(type default)
			)
			(layer "B.SilkS")
		)
		(fp_line
			(start 0.67945 0.3048)
			(end 0.67945 -0.305054)
			(stroke
				(width 0.1)
				(type default)
			)
			(layer "B.Fab")
		)
		(fp_line
			(start 0.67945 -0.305054)
			(end 0.12065 -0.305054)
			(stroke
				(width 0.1)
				(type default)
			)
			(layer "B.Fab")
		)
		(fp_line
			(start 0.12065 0.3048)
			(end 0.67945 0.3048)
			(stroke
				(width 0.1)
				(type default)
			)
			(layer "B.Fab")
		)
		(fp_line
			(start 0.12065 0.2794)
			(end 0.12065 0.3048)
			(stroke
				(width 0.1)
				(type default)
			)
			(layer "B.Fab")
		)
		(fp_line
			(start 0.12065 -0.2794)
			(end -0.12065 -0.2794)
			(stroke
				(width 0.1)
				(type default)
			)
			(layer "B.Fab")
		)
		(fp_line
			(start 0.12065 -0.305054)
			(end 0.12065 -0.2794)
			(stroke
				(width 0.1)
				(type default)
			)
			(layer "B.Fab")
		)
		(fp_line
			(start -0.120396 0.3048)
			(end -0.120396 0.2794)
			(stroke
				(width 0.1)
				(type default)
			)
			(layer "B.Fab")
		)
		(fp_line
			(start -0.120396 0.2794)
			(end 0.12065 0.2794)
			(stroke
				(width 0.1)
				(type default)
			)
			(layer "B.Fab")
		)
		(fp_line
			(start -0.12065 -0.2794)
			(end -0.12065 -0.3048)
			(stroke
				(width 0.1)
				(type default)
			)
			(layer "B.Fab")
		)
		(fp_line
			(start -0.12065 -0.3048)
			(end -0.67945 -0.3048)
			(stroke
				(width 0.1)
				(type default)
			)
			(layer "B.Fab")
		)
		(fp_line
			(start -0.67945 0.3048)
			(end -0.120396 0.3048)
			(stroke
				(width 0.1)
				(type default)
			)
			(layer "B.Fab")
		)
		(fp_line
			(start -0.67945 -0.3048)
			(end -0.67945 0.3048)
			(stroke
				(width 0.1)
				(type default)
			)
			(layer "B.Fab")
		)
		(pad "1" smd circle
			(at 0.40005 0)
			(size 0 0)
			(layers "B.Cu" "B.Mask" "B.Paste")
			(net "PVDDCR_CPU0_P1")
		)
		(pad "2" smd circle
			(at -0.40005 0)
			(size 0 0)
			(layers "B.Cu" "B.Mask" "B.Paste")
			(net "GND")
		)
	)
	(footprint ""
		(layer "B.Cu")
		(at 172.593 -98.135948 90)
		(property "Reference" "R6023"
			(at 0 0 90)
			(layer "B.SilkS")
			(hide yes)
			(effects
				(font
					(size 1.27 1.27)
				)
				(justify mirror)
			)
		)
		(property "Value" ""
			(at 0 0 90)
			(layer "B.Fab")
			(effects
				(font
					(size 1.27 1.27)
				)
				(justify mirror)
			)
		)
		(duplicate_pad_numbers_are_jumpers no)
		(fp_line
			(start 0.7874 -0.4064)
			(end -0.7874 -0.4064)
			(stroke
				(width 0.1524)
				(type default)
			)
			(layer "B.SilkS")
		)
		(fp_line
			(start -0.7874 -0.4064)
			(end -0.7874 0.4064)
			(stroke
				(width 0.1524)
				(type default)
			)
			(layer "B.SilkS")
		)
		(fp_line
			(start 0.7874 0.4064)
			(end 0.7874 -0.4064)
			(stroke
				(width 0.1524)
				(type default)
			)
			(layer "B.SilkS")
		)
		(fp_line
			(start -0.7874 0.4064)
			(end 0.7874 0.4064)
			(stroke
				(width 0.1524)
				(type default)
			)
			(layer "B.SilkS")
		)
		(fp_line
			(start 0.67945 -0.305054)
			(end 0.12065 -0.305054)
			(stroke
				(width 0.1)
				(type default)
			)
			(layer "B.Fab")
		)
		(fp_line
			(start 0.12065 -0.305054)
			(end 0.12065 -0.2794)
			(stroke
				(width 0.1)
				(type default)
			)
			(layer "B.Fab")
		)
		(fp_line
			(start -0.12065 -0.3048)
			(end -0.67945 -0.3048)
			(stroke
				(width 0.1)
				(type default)
			)
			(layer "B.Fab")
		)
		(fp_line
			(start -0.67945 -0.3048)
			(end -0.67945 0.3048)
			(stroke
				(width 0.1)
				(type default)
			)
			(layer "B.Fab")
		)
		(fp_line
			(start 0.12065 -0.2794)
			(end -0.12065 -0.2794)
			(stroke
				(width 0.1)
				(type default)
			)
			(layer "B.Fab")
		)
		(fp_line
			(start -0.12065 -0.2794)
			(end -0.12065 -0.3048)
			(stroke
				(width 0.1)
				(type default)
			)
			(layer "B.Fab")
		)
		(fp_line
			(start 0.12065 0.2794)
			(end 0.12065 0.3048)
			(stroke
				(width 0.1)
				(type default)
			)
			(layer "B.Fab")
		)
		(fp_line
			(start -0.120396 0.2794)
			(end 0.12065 0.2794)
			(stroke
				(width 0.1)
				(type default)
			)
			(layer "B.Fab")
		)
		(fp_line
			(start 0.67945 0.3048)
			(end 0.67945 -0.305054)
			(stroke
				(width 0.1)
				(type default)
			)
			(layer "B.Fab")
		)
		(fp_line
			(start 0.12065 0.3048)
			(end 0.67945 0.3048)
			(stroke
				(width 0.1)
				(type default)
			)
			(layer "B.Fab")
		)
		(fp_line
			(start -0.120396 0.3048)
			(end -0.120396 0.2794)
			(stroke
				(width 0.1)
				(type default)
			)
			(layer "B.Fab")
		)
		(fp_line
			(start -0.67945 0.3048)
			(end -0.120396 0.3048)
			(stroke
				(width 0.1)
				(type default)
			)
			(layer "B.Fab")
		)
		(pad "1" smd circle
			(at 0.40005 0 270)
			(size 0 0)
			(layers "B.Cu" "B.Mask" "B.Paste")
			(net "P3V3_AUX")
		)
		(pad "2" smd circle
			(at -0.40005 0 270)
			(size 0 0)
			(layers "B.Cu" "B.Mask" "B.Paste")
			(net "SGPIO_SCM_LD_<1>")
		)
	)
)
